%FSTAX23Y23*%
%MOIN*%
%SFA1B1*%

%IPPOS*%
%ADD79R,0.314960X0.135830*%
%ADD80R,1.354330X0.230320*%
%ADD105R,0.036000X0.173000*%
%ADD106R,0.036000X0.134000*%
%ADD116R,0.065090X0.053280*%
%ADD118R,0.033200X0.034770*%
%ADD125R,0.053280X0.065090*%
%ADD126R,0.034770X0.033200*%
%ADD131R,0.090870X0.052090*%
%ADD133C,0.039500*%
%ADD134C,0.073980*%
%ADD135C,0.008000*%
%ADD136C,0.069020*%
%ADD137R,0.069020X0.069020*%
%ADD138C,0.083000*%
%ADD139C,0.106420*%
%ADD140O,0.096580X0.185170*%
%ADD141O,0.185170X0.096580*%
%ADD142O,0.204850X0.106420*%
%ADD143C,0.120000*%
%ADD144C,0.128000*%
%ADD145R,0.008000X0.008000*%
%ADD146C,0.029660*%
%ADD147C,0.063000*%
%ADD148R,0.063000X0.063000*%
%ADD149C,0.058000*%
%ADD150C,0.258000*%
%ADD151C,0.024000*%
%ADD152C,0.208000*%
%LNgrandmaster-1*%
%LPD*%
G54D79*
X0147Y00245D03*
G54D80*
X02446Y00111D03*
G54D105*
X01915Y00137D03*
X02545D03*
X02624D03*
X02899D03*
X03057D03*
X02742D03*
X02938D03*
X02781D03*
X02309D03*
X02427D03*
X02584D03*
X02072D03*
X02033D03*
X01994D03*
X01954D03*
X0219D03*
X02348D03*
X02387D03*
X02466D03*
X02505D03*
X0282D03*
X02663D03*
X0286D03*
X02978D03*
X03017D03*
X02702D03*
X02112D03*
X02151D03*
X01836D03*
X01875D03*
X03096D03*
G54D106*
X01797Y00157D03*
G54D116*
X02632Y02971D03*
Y03042D03*
G54D118*
X02349Y00329D03*
Y00362D03*
X02389D03*
Y00329D03*
X02468D03*
Y00362D03*
X02511D03*
Y00329D03*
X02664Y00362D03*
Y00329D03*
X02704Y00362D03*
Y00329D03*
X02819Y00362D03*
Y00329D03*
X02854D03*
Y00362D03*
X02979D03*
Y00329D03*
X03019Y00362D03*
Y00329D03*
X02711Y03003D03*
Y03036D03*
G54D125*
X02398Y02944D03*
X02327D03*
G54D126*
X02385Y02854D03*
X02351D03*
G54D131*
X02334Y03279D03*
Y032D03*
Y03121D03*
Y03042D03*
X02509Y03279D03*
Y03121D03*
Y032D03*
Y03042D03*
G54D133*
X03958Y04126D03*
X03784D03*
G54D134*
X03294Y04086D03*
X02994D03*
G54D135*
X02422Y03082D03*
Y03239D03*
Y03601D03*
Y03443D03*
G54D136*
X05327Y02307D03*
X05127D03*
X04927D03*
X04727D03*
X04927Y01007D03*
X05127D03*
X04327Y02307D03*
X05327Y01007D03*
G54D137*
X04327Y01007D03*
G54D138*
X05578Y0089D03*
Y01689D03*
Y02489D03*
X03979D03*
Y0089D03*
X04062Y02595D03*
X0418D03*
X04298D03*
G54D139*
X05723Y04025D03*
Y03844D03*
X069Y03806D03*
Y03589D03*
X06734D03*
Y03806D03*
X06569Y03589D03*
Y03806D03*
G54D140*
X05934Y03937D03*
G54D141*
X06119Y04056D03*
G54D142*
X06119Y03819D03*
G54D143*
X00199Y00906D03*
Y02481D03*
Y01956D03*
Y01431D03*
G54D144*
X00299Y01006D03*
Y00806D03*
X00099D03*
Y01006D03*
X00299Y02581D03*
Y02381D03*
X00099D03*
Y02581D03*
X00299Y02056D03*
Y01856D03*
X00099D03*
Y02056D03*
X00299Y01531D03*
Y01331D03*
X00099D03*
Y01531D03*
G54D145*
X03617Y02486D03*
X01652Y00916D03*
X01651Y02486D03*
X03617Y00916D03*
G54D146*
X03571Y02097D03*
Y01309D03*
X02203Y02438D03*
X01696Y01309D03*
Y02097D03*
X02203Y00958D03*
X0299D03*
X0299Y02438D03*
G54D147*
X02043Y04157D03*
Y04057D03*
X01457Y04153D03*
Y04053D03*
G54D148*
X02043Y04257D03*
X01457Y04253D03*
G54D149*
X069Y04093D03*
X06569D03*
G54D150*
X00285Y04152D03*
Y00368D03*
G54D151*
X04039Y03784D03*
X02494Y02661D03*
X02692Y02721D03*
X02511Y00405D03*
X0261Y00279D03*
X02578D03*
X0298Y00409D03*
X02821Y00407D03*
X02748Y00282D03*
X02469Y0041D03*
X02905Y00279D03*
X02878Y00249D03*
X02692Y00795D03*
X02665D03*
X02854Y00405D03*
X02779Y00279D03*
X02665Y00405D03*
X02704D03*
X0235D03*
X02389D03*
X02937Y00279D03*
X02957Y00251D03*
X03019Y00405D03*
X0274Y00976D03*
X02767D03*
X02732Y00795D03*
X02681Y00976D03*
X02708D03*
X02447Y00242D03*
X02413Y00279D03*
X02444D03*
X02606Y00931D03*
X02625Y00795D03*
X02598D03*
X02636Y00247D03*
X02799Y00251D03*
X02826Y00976D03*
X02799D03*
X02649D03*
X02622D03*
X02759Y00795D03*
X02799D03*
X02826D03*
X02862D03*
X02893D03*
X02409Y01088D03*
X02311Y0109D03*
X02508Y00931D03*
X02409Y00932D03*
X02724Y01093D03*
X02784Y01094D03*
X02842Y01095D03*
X02546Y00244D03*
X03097Y00251D03*
X02475Y02291D03*
X0233Y02215D03*
X01798Y01304D03*
X02606Y01091D03*
X03554Y01841D03*
X03719Y01996D03*
X03894Y01566D03*
X03379Y01386D03*
X01721Y0189D03*
X01671Y01792D03*
X01674Y01989D03*
X02508Y0109D03*
X03413Y01573D03*
X0167Y01595D03*
X01754Y02126D03*
X02409Y02579D03*
X02586Y02569D03*
X03197Y01714D03*
X03439Y0187D03*
X03298Y01971D03*
X02985Y02287D03*
X02702Y02289D03*
X02821Y02601D03*
X01718Y01792D03*
X02881Y02566D03*
X03732Y01418D03*
X03554Y01891D03*
X02253Y02279D03*
X02272Y02463D03*
X01719Y01536D03*
X02311Y00934D03*
X03571Y02033D03*
X03554Y01991D03*
X02942Y02286D03*
X02841Y02263D03*
X02394Y0272D03*
X01567Y01285D03*
X01675Y01891D03*
X01568Y02067D03*
X02783Y02429D03*
X03719Y01921D03*
X03773Y01666D03*
X02599Y02436D03*
X02494Y02696D03*
X02894Y02431D03*
X02665Y01092D03*
X02475Y02456D03*
X03414Y01805D03*
X03404Y01363D03*
X02579Y02281D03*
X02685Y02311D03*
X0359Y01662D03*
X02404Y02412D03*
X02803Y02307D03*
X01716Y01399D03*
X01721Y01989D03*
X01619Y02121D03*
X03549Y01413D03*
X02488Y02413D03*
X02726Y02293D03*
X01822Y01674D03*
X0167Y01694D03*
X01884Y02071D03*
X02901Y01095D03*
X0292Y02428D03*
X01893Y01693D03*
X03594Y01514D03*
X0245Y02282D03*
X02409Y02314D03*
X02958Y02621D03*
X03406Y01461D03*
X0341Y01713D03*
X03252Y01661D03*
X02933Y00953D03*
X02871Y02297D03*
X02685Y02568D03*
X03571Y02058D03*
X03804Y0184D03*
X01879Y01811D03*
X03554Y01941D03*
X03392Y01871D03*
X03407Y01411D03*
X02575Y02412D03*
X02499Y02236D03*
X02409Y02283D03*
X02783Y02568D03*
X02948Y02456D03*
X03549Y01441D03*
X03718Y01713D03*
X02624Y02461D03*
X01897Y01516D03*
X03834Y01481D03*
X03864Y01511D03*
X03924Y01536D03*
X03719Y01766D03*
X03329Y01826D03*
X02645Y02274D03*
X02665Y02291D03*
X01721Y01694D03*
X01671Y01399D03*
X02581Y02308D03*
X03803Y01691D03*
X03224Y01661D03*
X02252Y02613D03*
X01718Y01497D03*
X01714Y01595D03*
X01671Y01497D03*
X02321Y02586D03*
X03379Y01336D03*
X01797Y00355D03*
X02034Y00246D03*
X01916Y00244D03*
X02309Y00246D03*
X0333Y03301D03*
X0412Y03594D03*
X01393Y01816D03*
X0099Y00687D03*
X04794Y02808D03*
X03183Y03135D03*
X03277Y02963D03*
X03197Y0297D03*
X03491Y03103D03*
X03188Y03187D03*
X0323Y03235D03*
X03358Y03448D03*
X03068Y03395D03*
X02419Y02788D03*
X02146Y02753D03*
X03275Y03141D03*
X03056Y01811D03*
X02413Y03295D03*
X02254Y03536D03*
X02579Y03486D03*
X02389Y03481D03*
X02321Y03361D03*
X02434Y03546D03*
X02634Y03406D03*
X02631Y02876D03*
X02591Y03186D03*
X0259Y03288D03*
X00996Y02256D03*
X02004Y01336D03*
X02028Y01361D03*
X02549Y01755D03*
X02418Y03118D03*
X02414Y03199D03*
X02462Y03172D03*
X02473Y0298D03*
X02146Y04103D03*
X02253Y04086D03*
X01408Y0398D03*
X01345Y04175D03*
X00996Y01187D03*
X00988Y01717D03*
X00937Y02317D03*
X02353Y04017D03*
X01726Y04329D03*
X01788D03*
X04477Y03135D03*
X04064Y02722D03*
X06628Y01372D03*
X04039Y02406D03*
X06974Y01939D03*
X04134Y01651D03*
X03994Y01551D03*
X04134Y01751D03*
X04151Y01623D03*
X03968Y01671D03*
X03969Y01552D03*
X03944Y01816D03*
X04131Y01686D03*
X04179Y01601D03*
X04034Y01546D03*
X03996Y01711D03*
X04064Y01796D03*
Y01511D03*
X03263Y03303D03*
X0396Y02724D03*
X01569Y04171D03*
X02076Y00255D03*
Y00287D03*
X02112D03*
X02151D03*
X02112Y00255D03*
X02151D03*
X01832D03*
X01852D03*
X01872D03*
X01832Y00287D03*
X01852D03*
X01872D03*
X06253Y02909D03*
X06647Y03129D03*
X05267Y04088D03*
X04339Y02725D03*
X04503Y02789D03*
X02231Y02584D03*
X05994Y03552D03*
X04049Y03665D03*
X03829Y03806D03*
X05577Y02214D03*
X02694Y01481D03*
X02384Y01941D03*
X0383Y03762D03*
X06334Y03266D03*
X03744Y03261D03*
X03395Y04222D03*
X04272Y03135D03*
X05634Y02236D03*
X02626Y0177D03*
X06304Y03121D03*
X03939D03*
X02139Y03738D03*
X04208Y03135D03*
X02604Y01734D03*
X06626Y03032D03*
X04152Y03135D03*
X02299Y01916D03*
X02724Y03521D03*
X01248Y02D03*
X02579Y0179D03*
X04068Y03135D03*
X02674Y03501D03*
X04234Y02725D03*
X06456Y03009D03*
X01691Y04079D03*
X03642Y00636D03*
X02259Y03261D03*
X03374Y03273D03*
X03368Y0305D03*
X06476Y03231D03*
X04333Y03135D03*
X01557Y04229D03*
X06282Y03226D03*
X03806Y03235D03*
X01261Y02482D03*
X04114Y03135D03*
X06648Y03341D03*
X02888Y04221D03*
X0337Y02888D03*
X02258Y03741D03*
X01749Y0411D03*
X0257Y04283D03*
X01459Y03147D03*
X0144Y03557D03*
X01903Y04018D03*
X0229Y04217D03*
X0388Y03109D03*
X03623Y02587D03*
X03622Y03486D03*
X03491Y03297D03*
X03542Y03319D03*
X03344Y02996D03*
X03744Y03342D03*
X03653Y03293D03*
X03394Y03447D03*
X03436Y03457D03*
X03717Y03072D03*
X02799Y03616D03*
X03589Y01711D03*
X05733Y03556D03*
X05676Y03546D03*
X03603Y00682D03*
X02478Y00937D03*
X06548Y01531D03*
X06602Y01612D03*
Y01672D03*
Y01722D03*
X06601Y01777D03*
X06685Y01828D03*
X06699Y01881D03*
X06949Y02095D03*
X06607Y02176D03*
X06395Y02111D03*
X06048Y02171D03*
X06004Y02434D03*
X06274Y02391D03*
X06398Y02453D03*
X06397Y02501D03*
X06396Y02556D03*
X06397Y0261D03*
X06398Y02657D03*
X06372Y02909D03*
X0491Y04203D03*
X04387Y04206D03*
X03777Y04023D03*
X04085Y03892D03*
X04194Y03884D03*
X04431Y03135D03*
X0286Y03787D03*
X02724Y03729D03*
X03531Y0366D03*
X03269Y03788D03*
X01242Y01472D03*
X01256Y00942D03*
X00654Y0079D03*
X00655Y01028D03*
X00654Y01314D03*
X00653Y01551D03*
X00654Y01839D03*
Y02073D03*
Y02365D03*
X00653Y02593D03*
X02206Y01298D03*
X02205Y032D03*
X02502Y01316D03*
X02525Y02463D03*
X03342Y02263D03*
X03498Y02341D03*
X02429Y02621D03*
X01004Y00906D03*
X02446Y01437D03*
X01008Y0143D03*
X02409Y01967D03*
X01009Y01956D03*
X0102Y02481D03*
X02643Y01616D03*
X02666Y0164D03*
X01884Y03601D03*
X01754Y03661D03*
X03424Y03636D03*
X01549Y03621D03*
X03239Y03596D03*
X01574D03*
X03539Y03806D03*
X03219D03*
X02722Y03786D03*
X02139Y03611D03*
X02084Y03896D03*
X02083Y01411D03*
X02059Y01386D03*
Y03871D03*
X02029Y03836D03*
X01294Y04256D03*
X02004Y03816D03*
X02234Y03506D03*
X03529Y03481D03*
X05274Y03511D03*
X06284Y02501D03*
X02679Y03661D03*
X02774Y03566D03*
X02993Y03751D03*
X03699D03*
X03014Y03831D03*
X03699Y03836D03*
X04254Y03776D03*
X02894Y01561D03*
X02919Y01536D03*
X02274Y01506D03*
X02719Y01591D03*
X03724Y01675D03*
X06844Y01661D03*
X06424Y02181D03*
X06309Y03199D03*
X06339Y03151D03*
X04754Y04115D03*
X01779Y04156D03*
X03504Y04086D03*
X03854Y03151D03*
X03829Y03176D03*
X03799Y03201D03*
X06439Y03191D03*
X06354Y03331D03*
X06444Y03291D03*
X03302Y03344D03*
X06409Y03371D03*
X06447Y03396D03*
X06479Y03426D03*
X06509Y03456D03*
X03469D03*
X01849Y03701D03*
X06294D03*
G54D152*
X02531Y03853D03*
Y0283D03*
X00149D03*
Y03853D03*
M02*